# BASEBOARD_FAB2 (Tioga Pass) — schematic netlist excerpt (pin names and nets, part order shuffled) for the footprints in the layout excerpt that follows; sources: Cadence DE-HDL packaged netlist, KiCad conversion of Wiwynn_Tioga_Pass_MB.brd

R8D29  RES  4.75K 1% CHIP  pkg 0402  page 89 : A = P3V3_STBY ; B = IRQ_DIMM_SAVE_LVT3
C5T3  CAP_A  47UF 4V 20% X5R  pkg 0603V  page 221 : A = PVTT_ABC ; B = GND
C8U3  CAP_A  47UF 4V 20% X5R  pkg 0603V  page 225 : A = PVDDQ_GHJ ; B = GND

(kicad_pcb
	(version 20260206)
	(generator "pcbnew")
	(generator_version "10.0")
	(general
		(thickness 1.6)
		(legacy_teardrops no)
	)
	(paper "A4")
	(title_block
		(title "Wiwynn_Tioga_Pass_MB.brd")
		(comment 1 "Tioga Pass / footprints 4712-4714 of 4770")
	)
	(layers
		(0 "F.Cu" signal "TOP")
		(4 "In1.Cu" signal "L2GND")
		(6 "In2.Cu" signal "L3")
		(8 "In3.Cu" signal "L4GND")
		(10 "In4.Cu" signal "L5")
		(12 "In5.Cu" signal "L6GND")
		(14 "In6.Cu" signal "L7VCC")
		(16 "In7.Cu" signal "L8VCC")
		(18 "In8.Cu" signal "L9GND")
		(20 "In9.Cu" signal "L10")
		(22 "In10.Cu" signal "L11GND")
		(24 "In11.Cu" signal "L12")
		(26 "In12.Cu" signal "L13GND")
		(2 "B.Cu" signal "BOTTOM")
		(9 "F.Adhes" user "F.Adhesive")
		(11 "B.Adhes" user "B.Adhesive")
		(13 "F.Paste" user "Package Geometry/Pastemask Top")
		(15 "B.Paste" user "Package Geometry/Pastemask Bottom")
		(5 "F.SilkS" user "Ref Des/Silkscreen Top")
		(7 "B.SilkS" user "Ref Des/Silkscreen Bottom")
		(1 "F.Mask" user "Board Geometry/Soldermask Top")
		(3 "B.Mask" user "Board Geometry/Soldermask Bottom")
		(17 "Dwgs.User" user "User.Drawings")
		(19 "Cmts.User" user "User.Comments")
		(21 "Eco1.User" user "User.Eco1")
		(23 "Eco2.User" user "User.Eco2")
		(25 "Edge.Cuts" user "Board Geometry/Outline")
		(27 "Margin" user)
		(31 "F.CrtYd" user "Package Geometry/Place Bound Top")
		(29 "B.CrtYd" user "Package Geometry/Place Bound Bottom")
		(35 "F.Fab" user "Ref Des/Assembly Top")
		(33 "B.Fab" user "Ref Des/Assembly Bottom")
	)
	(footprint ""
		(layer "B.Cu")
		(at 260.6802 -26.475182 -90)
		(property "Reference" "C5T3"
			(at 0 0 90)
			(layer "B.SilkS")
			(hide yes)
			(effects
				(font
					(size 1.27 1.27)
				)
				(justify mirror)
			)
		)
		(property "Value" ""
			(at 0 0 90)
			(layer "B.Fab")
			(effects
				(font
					(size 1.27 1.27)
				)
				(justify mirror)
			)
		)
		(duplicate_pad_numbers_are_jumpers no)
		(fp_rect
			(start 0.500126 1.598422)
			(end -0.500126 -0.201422)
			(stroke
				(width 0)
				(type default)
			)
			(fill no)
			(layer "B.CrtYd")
		)
		(fp_line
			(start -0.500126 1.598422)
			(end 0.500126 1.598422)
			(stroke
				(width 0.1)
				(type default)
			)
			(layer "B.Fab")
		)
		(fp_line
			(start 0.500126 1.598422)
			(end 0.500126 -0.201422)
			(stroke
				(width 0.1)
				(type default)
			)
			(layer "B.Fab")
		)
		(fp_line
			(start -0.500126 -0.201422)
			(end -0.500126 1.598422)
			(stroke
				(width 0.1)
				(type default)
			)
			(layer "B.Fab")
		)
		(fp_line
			(start 0.500126 -0.201422)
			(end -0.500126 -0.201422)
			(stroke
				(width 0.1)
				(type default)
			)
			(layer "B.Fab")
		)
		(pad "1" smd rect
			(at 0 0 180)
			(size 0.889 0.9906)
			(layers "B.Cu" "B.Mask" "B.Paste")
			(net "PVTT_ABC")
		)
		(pad "2" smd rect
			(at 0 1.397 180)
			(size 0.889 0.9906)
			(layers "B.Cu" "B.Mask" "B.Paste")
			(net "GND")
		)
		(zone
			(layer "B.Cu")
			(hatch none 0.5)
			(connect_pads
				(clearance 0)
			)
			(min_thickness 0.25)
			(keepout
				(tracks not_allowed)
				(vias allowed)
				(pads allowed)
				(copperpour not_allowed)
				(footprints allowed)
			)
			(placement
				(enabled no)
				(sheetname "")
			)
			(fill
				(thermal_gap 0.5)
				(thermal_bridge_width 0.5)
				(island_removal_mode 0)
			)
			(polygon
				(pts
					(xy 259.7277 -25.979882) (xy 260.2357 -25.979882) (xy 260.2357 -26.970482) (xy 259.7277 -26.970482)
				)
			)
		)
		(zone
			(layer "B.Cu")
			(hatch none 0.5)
			(connect_pads
				(clearance 0)
			)
			(min_thickness 0.25)
			(keepout
				(tracks allowed)
				(vias not_allowed)
				(pads allowed)
				(copperpour not_allowed)
				(footprints allowed)
			)
			(placement
				(enabled no)
				(sheetname "")
			)
			(fill
				(thermal_gap 0.5)
				(thermal_bridge_width 0.5)
				(island_removal_mode 0)
			)
			(polygon
				(pts
					(xy 259.7277 -25.979882) (xy 260.2357 -25.979882) (xy 260.2357 -26.970482) (xy 259.7277 -26.970482)
				)
			)
		)
	)
	(footprint ""
		(layer "B.Cu")
		(at 101.3968 -8.1534 90)
		(property "Reference" "C8U3"
			(at -1.848866 0.752348 90)
			(unlocked yes)
			(layer "B.SilkS")
			(effects
				(font
					(size 1.27 0.9652)
					(thickness 0.1524)
				)
				(justify mirror)
			)
		)
		(property "Value" ""
			(at 0 0 90)
			(layer "B.Fab")
			(effects
				(font
					(size 1.27 1.27)
				)
				(justify mirror)
			)
		)
		(duplicate_pad_numbers_are_jumpers no)
		(fp_rect
			(start 0.500126 1.598422)
			(end -0.500126 -0.201422)
			(stroke
				(width 0)
				(type default)
			)
			(fill no)
			(layer "B.CrtYd")
		)
		(fp_line
			(start 0.500126 -0.201422)
			(end -0.500126 -0.201422)
			(stroke
				(width 0.1)
				(type default)
			)
			(layer "B.Fab")
		)
		(fp_line
			(start -0.500126 -0.201422)
			(end -0.500126 1.598422)
			(stroke
				(width 0.1)
				(type default)
			)
			(layer "B.Fab")
		)
		(fp_line
			(start 0.500126 1.598422)
			(end 0.500126 -0.201422)
			(stroke
				(width 0.1)
				(type default)
			)
			(layer "B.Fab")
		)
		(fp_line
			(start -0.500126 1.598422)
			(end 0.500126 1.598422)
			(stroke
				(width 0.1)
				(type default)
			)
			(layer "B.Fab")
		)
		(pad "1" smd rect
			(at 0 0)
			(size 0.889 0.9906)
			(layers "B.Cu" "B.Mask" "B.Paste")
			(net "PVDDQ_GHJ")
		)
		(pad "2" smd rect
			(at 0 1.397)
			(size 0.889 0.9906)
			(layers "B.Cu" "B.Mask" "B.Paste")
			(net "GND")
		)
		(zone
			(layer "B.Cu")
			(hatch none 0.5)
			(connect_pads
				(clearance 0)
			)
			(min_thickness 0.25)
			(keepout
				(tracks allowed)
				(vias not_allowed)
				(pads allowed)
				(copperpour not_allowed)
				(footprints allowed)
			)
			(placement
				(enabled no)
				(sheetname "")
			)
			(fill
				(thermal_gap 0.5)
				(thermal_bridge_width 0.5)
				(island_removal_mode 0)
			)
			(polygon
				(pts
					(xy 102.3493 -8.6487) (xy 101.8413 -8.6487) (xy 101.8413 -7.6581) (xy 102.3493 -7.6581)
				)
			)
		)
		(zone
			(layer "B.Cu")
			(hatch none 0.5)
			(connect_pads
				(clearance 0)
			)
			(min_thickness 0.25)
			(keepout
				(tracks not_allowed)
				(vias allowed)
				(pads allowed)
				(copperpour not_allowed)
				(footprints allowed)
			)
			(placement
				(enabled no)
				(sheetname "")
			)
			(fill
				(thermal_gap 0.5)
				(thermal_bridge_width 0.5)
				(island_removal_mode 0)
			)
			(polygon
				(pts
					(xy 102.3493 -8.6487) (xy 101.8413 -8.6487) (xy 101.8413 -7.6581) (xy 102.3493 -7.6581)
				)
			)
		)
	)
	(footprint ""
		(layer "B.Cu")
		(at 311.130696 -28.942792)
		(property "Reference" "R8D29"
			(at 0 0 0)
			(layer "B.SilkS")
			(hide yes)
			(effects
				(font
					(size 1.27 1.27)
				)
				(justify mirror)
			)
		)
		(property "Value" ""
			(at 0 0 0)
			(layer "B.Fab")
			(effects
				(font
					(size 1.27 1.27)
				)
				(justify mirror)
			)
		)
		(duplicate_pad_numbers_are_jumpers no)
		(fp_poly
			(pts
				(xy 0.2794 -0.1016) (xy -0.2794 -0.1016) (xy -0.2794 0.9906) (xy 0.2794 0.9906)
			)
			(stroke
				(width 0)
				(type default)
			)
			(fill no)
			(layer "B.CrtYd")
		)
		(fp_line
			(start -0.2794 -0.1016)
			(end 0.2794 -0.1016)
			(stroke
				(width 0.1)
				(type default)
			)
			(layer "B.Fab")
		)
		(fp_line
			(start -0.2794 0.9906)
			(end -0.2794 -0.1016)
			(stroke
				(width 0.1)
				(type default)
			)
			(layer "B.Fab")
		)
		(fp_line
			(start 0.2794 -0.1016)
			(end 0.2794 0.9906)
			(stroke
				(width 0.1)
				(type default)
			)
			(layer "B.Fab")
		)
		(fp_line
			(start 0.2794 0.9906)
			(end -0.2794 0.9906)
			(stroke
				(width 0.1)
				(type default)
			)
			(layer "B.Fab")
		)
		(pad "1" smd rect
			(at 0 0 180)
			(size 0.508 0.508)
			(layers "B.Cu" "B.Mask" "B.Paste")
			(net "P3V3_STBY")
		)
		(pad "2" smd rect
			(at 0 0.889 180)
			(size 0.508 0.508)
			(layers "B.Cu" "B.Mask" "B.Paste")
			(net "IRQ_DIMM_SAVE_LVT3")
		)
		(zone
			(layer "B.Cu")
			(hatch none 0.5)
			(connect_pads
				(clearance 0)
			)
			(min_thickness 0.25)
			(keepout
				(tracks allowed)
				(vias not_allowed)
				(pads allowed)
				(copperpour not_allowed)
				(footprints allowed)
			)
			(placement
				(enabled no)
				(sheetname "")
			)
			(fill
				(thermal_gap 0.5)
				(thermal_bridge_width 0.5)
				(island_removal_mode 0)
			)
			(polygon
				(pts
					(xy 311.384696 -28.688792) (xy 310.876696 -28.688792) (xy 310.876696 -28.307792) (xy 311.384696 -28.307792)
				)
			)
		)
		(zone
			(layer "B.Cu")
			(hatch none 0.5)
			(connect_pads
				(clearance 0)
			)
			(min_thickness 0.25)
			(keepout
				(tracks not_allowed)
				(vias allowed)
				(pads allowed)
				(copperpour not_allowed)
				(footprints allowed)
			)
			(placement
				(enabled no)
				(sheetname "")
			)
			(fill
				(thermal_gap 0.5)
				(thermal_bridge_width 0.5)
				(island_removal_mode 0)
			)
			(polygon
				(pts
					(xy 311.384696 -28.307792) (xy 310.876696 -28.307792) (xy 310.876696 -28.688792) (xy 311.384696 -28.688792)
				)
			)
		)
	)
)
